# T6G (Grand Teton) — schematic netlist excerpt (pin names and nets, part order shuffled) for the footprints in the layout excerpt that follows; sources: Cadence DE-HDL packaged netlist, KiCad conversion of 04192023_DAF0TMB3IC0_F0TG_MB_C_brd_V02_OCP.brd

C1038  Q_CAP  4.7UF 6.3V 20% X6S  pkg 0402  page 312 : A = P0V9_CPU0_RT_2D ; B = GND
C1127  Q_CAP  0.1UF 16V 10% X7R  pkg C0402  page 83 : A = P1V8_AUX ; B = GND
C150  Q_CAP  10UF 25V 10% X6S  pkg C0805  page 89 : A = P12V_MEM_CPU0 ; B = GND

(kicad_pcb
	(version 20260206)
	(generator "pcbnew")
	(generator_version "10.0")
	(general
		(thickness 1.6)
		(legacy_teardrops no)
	)
	(paper "A4")
	(title_block
		(title "04192023_DAF0TMB3IC0_F0TG_MB_C_brd_V02_OCP.brd")
		(comment 1 "Grand Teton / footprints 5279-5281 of 8354")
	)
	(layers
		(0 "F.Cu" signal "TOP")
		(4 "In1.Cu" signal "GND")
		(6 "In2.Cu" signal "IN1")
		(8 "In3.Cu" signal "GND1")
		(10 "In4.Cu" signal "IN2")
		(12 "In5.Cu" signal "GND2")
		(14 "In6.Cu" signal "IN3")
		(16 "In7.Cu" signal "GND3")
		(18 "In8.Cu" signal "VCC")
		(20 "In9.Cu" signal "VCC1")
		(22 "In10.Cu" signal "GND4")
		(24 "In11.Cu" signal "IN4")
		(26 "In12.Cu" signal "GND5")
		(28 "In13.Cu" signal "IN5")
		(30 "In14.Cu" signal "GND6")
		(32 "In15.Cu" signal "IN6")
		(34 "In16.Cu" signal "GND7")
		(2 "B.Cu" signal "BOTTOM")
		(9 "F.Adhes" user "F.Adhesive")
		(11 "B.Adhes" user "B.Adhesive")
		(13 "F.Paste" user "Package Geometry/Pastemask Top")
		(15 "B.Paste" user "Package Geometry/Pastemask Bottom")
		(5 "F.SilkS" user "Ref Des/Silkscreen Top")
		(7 "B.SilkS" user "Ref Des/Silkscreen Bottom")
		(1 "F.Mask" user "Board Geometry/Soldermask Top")
		(3 "B.Mask" user "Board Geometry/Soldermask Bottom")
		(17 "Dwgs.User" user "User.Drawings")
		(19 "Cmts.User" user "User.Comments")
		(21 "Eco1.User" user "User.Eco1")
		(23 "Eco2.User" user "User.Eco2")
		(25 "Edge.Cuts" user "Board Geometry/Outline")
		(27 "Margin" user)
		(31 "F.CrtYd" user "Package Geometry/Place Bound Top")
		(29 "B.CrtYd" user "Package Geometry/Place Bound Bottom")
		(35 "F.Fab" user "Ref Des/Assembly Top")
		(33 "B.Fab" user "Ref Des/Assembly Bottom")
	)
	(footprint ""
		(layer "B.Cu")
		(at 284.736286 -192.660016)
		(property "Reference" "C150"
			(at 0 0 0)
			(layer "B.SilkS")
			(hide yes)
			(effects
				(font
					(size 1.27 1.27)
				)
				(justify mirror)
			)
		)
		(property "Value" ""
			(at 0 0 0)
			(layer "B.Fab")
			(effects
				(font
					(size 1.27 1.27)
				)
				(justify mirror)
			)
		)
		(duplicate_pad_numbers_are_jumpers no)
		(fp_line
			(start -1.524 -0.762)
			(end -1.524 0.762)
			(stroke
				(width 0.1524)
				(type default)
			)
			(layer "B.SilkS")
		)
		(fp_line
			(start -1.524 0.762)
			(end 1.524 0.762)
			(stroke
				(width 0.1524)
				(type default)
			)
			(layer "B.SilkS")
		)
		(fp_line
			(start 1.524 -0.762)
			(end -1.524 -0.762)
			(stroke
				(width 0.1524)
				(type default)
			)
			(layer "B.SilkS")
		)
		(fp_line
			(start 1.524 0.762)
			(end 1.524 -0.762)
			(stroke
				(width 0.1524)
				(type default)
			)
			(layer "B.SilkS")
		)
		(fp_line
			(start -1.1049 -0.724916)
			(end 1.1049 -0.724916)
			(stroke
				(width 0.1)
				(type default)
			)
			(layer "B.Fab")
		)
		(fp_line
			(start -1.1049 0.724916)
			(end -1.1049 -0.724916)
			(stroke
				(width 0.1)
				(type default)
			)
			(layer "B.Fab")
		)
		(fp_line
			(start 1.1049 -0.724916)
			(end 1.1049 0.724916)
			(stroke
				(width 0.1)
				(type default)
			)
			(layer "B.Fab")
		)
		(fp_line
			(start 1.1049 0.724916)
			(end -1.1049 0.724916)
			(stroke
				(width 0.1)
				(type default)
			)
			(layer "B.Fab")
		)
		(pad "1" smd rect
			(at 0.889 0)
			(size 1.016 1.27)
			(layers "B.Cu" "B.Mask" "B.Paste")
			(net "P12V_MEM_CPU0")
		)
		(pad "2" smd rect
			(at -0.889 0)
			(size 1.016 1.27)
			(layers "B.Cu" "B.Mask" "B.Paste")
			(net "GND")
		)
	)
	(footprint ""
		(layer "B.Cu")
		(at 376.491246 -398.942052 90)
		(property "Reference" "C1038"
			(at 0 0 90)
			(layer "B.SilkS")
			(hide yes)
			(effects
				(font
					(size 1.27 1.27)
				)
				(justify mirror)
			)
		)
		(property "Value" ""
			(at 0 0 90)
			(layer "B.Fab")
			(effects
				(font
					(size 1.27 1.27)
				)
				(justify mirror)
			)
		)
		(duplicate_pad_numbers_are_jumpers no)
		(fp_line
			(start 0.7874 -0.4064)
			(end -0.7874 -0.4064)
			(stroke
				(width 0.1524)
				(type default)
			)
			(layer "B.SilkS")
		)
		(fp_line
			(start -0.7874 -0.4064)
			(end -0.7874 0.4064)
			(stroke
				(width 0.1524)
				(type default)
			)
			(layer "B.SilkS")
		)
		(fp_line
			(start 0.7874 0.4064)
			(end 0.7874 -0.4064)
			(stroke
				(width 0.1524)
				(type default)
			)
			(layer "B.SilkS")
		)
		(fp_line
			(start -0.7874 0.4064)
			(end 0.7874 0.4064)
			(stroke
				(width 0.1524)
				(type default)
			)
			(layer "B.SilkS")
		)
		(fp_line
			(start 0.67945 -0.305054)
			(end 0.12065 -0.305054)
			(stroke
				(width 0.1)
				(type default)
			)
			(layer "B.Fab")
		)
		(fp_line
			(start 0.12065 -0.305054)
			(end 0.12065 -0.2794)
			(stroke
				(width 0.1)
				(type default)
			)
			(layer "B.Fab")
		)
		(fp_line
			(start -0.12065 -0.3048)
			(end -0.67945 -0.3048)
			(stroke
				(width 0.1)
				(type default)
			)
			(layer "B.Fab")
		)
		(fp_line
			(start -0.67945 -0.3048)
			(end -0.67945 0.3048)
			(stroke
				(width 0.1)
				(type default)
			)
			(layer "B.Fab")
		)
		(fp_line
			(start 0.12065 -0.2794)
			(end -0.12065 -0.2794)
			(stroke
				(width 0.1)
				(type default)
			)
			(layer "B.Fab")
		)
		(fp_line
			(start -0.12065 -0.2794)
			(end -0.12065 -0.3048)
			(stroke
				(width 0.1)
				(type default)
			)
			(layer "B.Fab")
		)
		(fp_line
			(start 0.12065 0.2794)
			(end 0.12065 0.3048)
			(stroke
				(width 0.1)
				(type default)
			)
			(layer "B.Fab")
		)
		(fp_line
			(start -0.120396 0.2794)
			(end 0.12065 0.2794)
			(stroke
				(width 0.1)
				(type default)
			)
			(layer "B.Fab")
		)
		(fp_line
			(start 0.67945 0.3048)
			(end 0.67945 -0.305054)
			(stroke
				(width 0.1)
				(type default)
			)
			(layer "B.Fab")
		)
		(fp_line
			(start 0.12065 0.3048)
			(end 0.67945 0.3048)
			(stroke
				(width 0.1)
				(type default)
			)
			(layer "B.Fab")
		)
		(fp_line
			(start -0.120396 0.3048)
			(end -0.120396 0.2794)
			(stroke
				(width 0.1)
				(type default)
			)
			(layer "B.Fab")
		)
		(fp_line
			(start -0.67945 0.3048)
			(end -0.120396 0.3048)
			(stroke
				(width 0.1)
				(type default)
			)
			(layer "B.Fab")
		)
		(pad "1" smd circle
			(at 0.40005 0 270)
			(size 0 0)
			(layers "B.Cu" "B.Mask" "B.Paste")
			(net "P0V9_CPU0_RT_2D")
		)
		(pad "2" smd circle
			(at -0.40005 0 270)
			(size 0 0)
			(layers "B.Cu" "B.Mask" "B.Paste")
			(net "GND")
		)
	)
	(footprint ""
		(layer "B.Cu")
		(at 182.732172 -111.863124 -90)
		(property "Reference" "C1127"
			(at 0 0 90)
			(layer "B.SilkS")
			(hide yes)
			(effects
				(font
					(size 1.27 1.27)
				)
				(justify mirror)
			)
		)
		(property "Value" ""
			(at 0 0 90)
			(layer "B.Fab")
			(effects
				(font
					(size 1.27 1.27)
				)
				(justify mirror)
			)
		)
		(duplicate_pad_numbers_are_jumpers no)
		(fp_line
			(start -0.69215 0.2921)
			(end 0.69215 0.2921)
			(stroke
				(width 0.1524)
				(type default)
			)
			(layer "B.SilkS")
		)
		(fp_line
			(start 0.69215 0.2921)
			(end 0.69215 -0.2921)
			(stroke
				(width 0.1524)
				(type default)
			)
			(layer "B.SilkS")
		)
		(fp_line
			(start -0.69215 -0.2921)
			(end -0.69215 0.2921)
			(stroke
				(width 0.1524)
				(type default)
			)
			(layer "B.SilkS")
		)
		(fp_line
			(start 0.69215 -0.2921)
			(end -0.69215 -0.2921)
			(stroke
				(width 0.1524)
				(type default)
			)
			(layer "B.SilkS")
		)
		(fp_line
			(start -0.51435 0.2794)
			(end 0.51435 0.2794)
			(stroke
				(width 0.1)
				(type default)
			)
			(layer "B.Fab")
		)
		(fp_line
			(start 0.51435 0.2794)
			(end 0.51435 -0.2794)
			(stroke
				(width 0.1)
				(type default)
			)
			(layer "B.Fab")
		)
		(fp_line
			(start -0.51435 -0.2794)
			(end -0.51435 0.2794)
			(stroke
				(width 0.1)
				(type default)
			)
			(layer "B.Fab")
		)
		(fp_line
			(start 0.51435 -0.2794)
			(end -0.51435 -0.2794)
			(stroke
				(width 0.1)
				(type default)
			)
			(layer "B.Fab")
		)
		(pad "1" smd circle
			(at 0.40005 0 90)
			(size 0 0)
			(layers "B.Cu" "B.Mask" "B.Paste")
			(net "P1V8_AUX")
		)
		(pad "2" smd circle
			(at -0.40005 0 90)
			(size 0 0)
			(layers "B.Cu" "B.Mask" "B.Paste")
			(net "GND")
		)
		(zone
			(layer "B.Cu")
			(hatch none 0.5)
			(connect_pads
				(clearance 0)
			)
			(min_thickness 0.25)
			(keepout
				(tracks not_allowed)
				(vias allowed)
				(pads allowed)
				(copperpour not_allowed)
				(footprints allowed)
			)
			(placement
				(enabled no)
				(sheetname "")
			)
			(fill
				(thermal_gap 0.5)
				(thermal_bridge_width 0.5)
				(island_removal_mode 0)
			)
			(polygon
				(pts
					(xy 182.586376 -111.764064) (xy 182.586376 -111.963454) (xy 182.644542 -112.053624) (xy 182.819802 -112.053624)
					(xy 182.878222 -111.963454) (xy 182.878222 -111.764064) (xy 182.820056 -111.672624) (xy 182.644542 -111.672624)
				)
			)
		)
	)
)
